(kicad_pcb
	(version 20260206)
	(generator "pcbnew")
	(generator_version "10.0")
	(general
		(thickness 1.6)
		(legacy_teardrops no)
	)
	(paper "A4")
	(title_block
		(title "03242023_DA0F0TMBIJ0_F0T_Motherboard_J_brd_V01_OCP.brd")
		(comment 1 "Grand Teton / footprints 629-636 of 6105")
	)
	(layers
		(0 "F.Cu" signal "TOP")
		(4 "In1.Cu" signal "GND")
		(6 "In2.Cu" signal "IN1")
		(8 "In3.Cu" signal "GND1")
		(10 "In4.Cu" signal "IN2")
		(12 "In5.Cu" signal "GND2")
		(14 "In6.Cu" signal "IN3")
		(16 "In7.Cu" signal "GND3")
		(18 "In8.Cu" signal "VCC")
		(20 "In9.Cu" signal "VCC1")
		(22 "In10.Cu" signal "GND4")
		(24 "In11.Cu" signal "IN4")
		(26 "In12.Cu" signal "GND5")
		(28 "In13.Cu" signal "IN5")
		(30 "In14.Cu" signal "GND6")
		(32 "In15.Cu" signal "IN6")
		(34 "In16.Cu" signal "GND7")
		(2 "B.Cu" signal "BOTTOM")
		(9 "F.Adhes" user "F.Adhesive")
		(11 "B.Adhes" user "B.Adhesive")
		(13 "F.Paste" user "Package Geometry/Pastemask Top")
		(15 "B.Paste" user "Package Geometry/Pastemask Bottom")
		(5 "F.SilkS" user "Ref Des/Silkscreen Top")
		(7 "B.SilkS" user "Ref Des/Silkscreen Bottom")
		(1 "F.Mask" user "Board Geometry/Soldermask Top")
		(3 "B.Mask" user "Board Geometry/Soldermask Bottom")
		(17 "Dwgs.User" user "User.Drawings")
		(19 "Cmts.User" user "User.Comments")
		(21 "Eco1.User" user "User.Eco1")
		(23 "Eco2.User" user "User.Eco2")
		(25 "Edge.Cuts" user "Board Geometry/Outline")
		(27 "Margin" user)
		(31 "F.CrtYd" user "Package Geometry/Place Bound Top")
		(29 "B.CrtYd" user "Package Geometry/Place Bound Bottom")
		(35 "F.Fab" user "Ref Des/Assembly Top")
		(33 "B.Fab" user "Ref Des/Assembly Bottom")
	)
	(footprint ""
		(layer "F.Cu")
		(at 429.299116 -109.26699 -90)
		(property "Reference" "PR3789"
			(at 0 0 270)
			(layer "F.SilkS")
			(hide yes)
			(effects
				(font
					(size 1.27 1.27)
				)
			)
		)
		(property "Value" ""
			(at 0 0 270)
			(layer "F.Fab")
			(effects
				(font
					(size 1.27 1.27)
				)
			)
		)
		(duplicate_pad_numbers_are_jumpers no)
		(fp_line
			(start -0.7874 0.4064)
			(end -0.7874 -0.4064)
			(stroke
				(width 0.1524)
				(type default)
			)
			(layer "F.SilkS")
		)
		(fp_line
			(start 0.7874 0.4064)
			(end -0.7874 0.4064)
			(stroke
				(width 0.1524)
				(type default)
			)
			(layer "F.SilkS")
		)
		(fp_line
			(start -0.7874 -0.4064)
			(end 0.7874 -0.4064)
			(stroke
				(width 0.1524)
				(type default)
			)
			(layer "F.SilkS")
		)
		(fp_line
			(start 0.7874 -0.4064)
			(end 0.7874 0.4064)
			(stroke
				(width 0.1524)
				(type default)
			)
			(layer "F.SilkS")
		)
		(fp_line
			(start -0.67945 0.3048)
			(end -0.67945 -0.305054)
			(stroke
				(width 0.1)
				(type default)
			)
			(layer "F.Fab")
		)
		(fp_line
			(start -0.12065 0.3048)
			(end -0.67945 0.3048)
			(stroke
				(width 0.1)
				(type default)
			)
			(layer "F.Fab")
		)
		(fp_line
			(start 0.120396 0.3048)
			(end 0.120396 0.2794)
			(stroke
				(width 0.1)
				(type default)
			)
			(layer "F.Fab")
		)
		(fp_line
			(start 0.67945 0.3048)
			(end 0.120396 0.3048)
			(stroke
				(width 0.1)
				(type default)
			)
			(layer "F.Fab")
		)
		(fp_line
			(start -0.12065 0.2794)
			(end -0.12065 0.3048)
			(stroke
				(width 0.1)
				(type default)
			)
			(layer "F.Fab")
		)
		(fp_line
			(start 0.120396 0.2794)
			(end -0.12065 0.2794)
			(stroke
				(width 0.1)
				(type default)
			)
			(layer "F.Fab")
		)
		(fp_line
			(start -0.12065 -0.2794)
			(end 0.12065 -0.2794)
			(stroke
				(width 0.1)
				(type default)
			)
			(layer "F.Fab")
		)
		(fp_line
			(start 0.12065 -0.2794)
			(end 0.12065 -0.3048)
			(stroke
				(width 0.1)
				(type default)
			)
			(layer "F.Fab")
		)
		(fp_line
			(start 0.12065 -0.3048)
			(end 0.67945 -0.3048)
			(stroke
				(width 0.1)
				(type default)
			)
			(layer "F.Fab")
		)
		(fp_line
			(start 0.67945 -0.3048)
			(end 0.67945 0.3048)
			(stroke
				(width 0.1)
				(type default)
			)
			(layer "F.Fab")
		)
		(fp_line
			(start -0.67945 -0.305054)
			(end -0.12065 -0.305054)
			(stroke
				(width 0.1)
				(type default)
			)
			(layer "F.Fab")
		)
		(fp_line
			(start -0.12065 -0.305054)
			(end -0.12065 -0.2794)
			(stroke
				(width 0.1)
				(type default)
			)
			(layer "F.Fab")
		)
		(pad "1" smd circle
			(at -0.40005 0 270)
			(size 0 0)
			(layers "F.Cu" "F.Mask" "F.Paste")
			(net "P3V3_AUX")
		)
		(pad "2" smd circle
			(at 0.40005 0 270)
			(size 0 0)
			(layers "F.Cu" "F.Mask" "F.Paste")
			(net "P3V3_OCP_UV_1")
		)
	)
	(footprint ""
		(layer "F.Cu")
		(at 380.58725 -402.371052 -90)
		(property "Reference" "C941"
			(at 0 0 270)
			(layer "F.SilkS")
			(hide yes)
			(effects
				(font
					(size 1.27 1.27)
				)
			)
		)
		(property "Value" ""
			(at 0 0 270)
			(layer "F.Fab")
			(effects
				(font
					(size 1.27 1.27)
				)
			)
		)
		(duplicate_pad_numbers_are_jumpers no)
		(fp_line
			(start -0.299974 0.150114)
			(end -0.299974 -0.150114)
			(stroke
				(width 0.1)
				(type default)
			)
			(layer "F.Fab")
		)
		(fp_line
			(start 0.299974 0.150114)
			(end -0.299974 0.150114)
			(stroke
				(width 0.1)
				(type default)
			)
			(layer "F.Fab")
		)
		(fp_line
			(start -0.299974 -0.150114)
			(end 0.299974 -0.150114)
			(stroke
				(width 0.1)
				(type default)
			)
			(layer "F.Fab")
		)
		(fp_line
			(start 0.299974 -0.150114)
			(end 0.299974 0.150114)
			(stroke
				(width 0.1)
				(type default)
			)
			(layer "F.Fab")
		)
		(pad "1" smd rect
			(at -0.2667 0 270)
			(size 0.3048 0.381)
			(layers "F.Cu" "F.Mask" "F.Paste")
			(net "P5E_CPU0_PE2_TX_C_DP<12>")
		)
		(pad "2" smd rect
			(at 0.2667 0 270)
			(size 0.3048 0.381)
			(layers "F.Cu" "F.Mask" "F.Paste")
			(net "P5E_CPU0_PE2_TX_DP<12>")
		)
	)
	(footprint ""
		(layer "F.Cu")
		(at 243.045234 -137.344658)
		(property "Reference" "R4714"
			(at 0 0 0)
			(layer "F.SilkS")
			(hide yes)
			(effects
				(font
					(size 1.27 1.27)
				)
			)
		)
		(property "Value" ""
			(at 0 0 0)
			(layer "F.Fab")
			(effects
				(font
					(size 1.27 1.27)
				)
			)
		)
		(duplicate_pad_numbers_are_jumpers no)
		(fp_line
			(start -0.7874 -0.4064)
			(end 0.7874 -0.4064)
			(stroke
				(width 0.1524)
				(type default)
			)
			(layer "F.SilkS")
		)
		(fp_line
			(start -0.7874 0.4064)
			(end -0.7874 -0.4064)
			(stroke
				(width 0.1524)
				(type default)
			)
			(layer "F.SilkS")
		)
		(fp_line
			(start 0.7874 -0.4064)
			(end 0.7874 0.4064)
			(stroke
				(width 0.1524)
				(type default)
			)
			(layer "F.SilkS")
		)
		(fp_line
			(start 0.7874 0.4064)
			(end -0.7874 0.4064)
			(stroke
				(width 0.1524)
				(type default)
			)
			(layer "F.SilkS")
		)
		(fp_line
			(start -0.67945 -0.305054)
			(end -0.12065 -0.305054)
			(stroke
				(width 0.1)
				(type default)
			)
			(layer "F.Fab")
		)
		(fp_line
			(start -0.67945 0.3048)
			(end -0.67945 -0.305054)
			(stroke
				(width 0.1)
				(type default)
			)
			(layer "F.Fab")
		)
		(fp_line
			(start -0.12065 -0.305054)
			(end -0.12065 -0.2794)
			(stroke
				(width 0.1)
				(type default)
			)
			(layer "F.Fab")
		)
		(fp_line
			(start -0.12065 -0.2794)
			(end 0.12065 -0.2794)
			(stroke
				(width 0.1)
				(type default)
			)
			(layer "F.Fab")
		)
		(fp_line
			(start -0.12065 0.2794)
			(end -0.12065 0.3048)
			(stroke
				(width 0.1)
				(type default)
			)
			(layer "F.Fab")
		)
		(fp_line
			(start -0.12065 0.3048)
			(end -0.67945 0.3048)
			(stroke
				(width 0.1)
				(type default)
			)
			(layer "F.Fab")
		)
		(fp_line
			(start 0.120396 0.2794)
			(end -0.12065 0.2794)
			(stroke
				(width 0.1)
				(type default)
			)
			(layer "F.Fab")
		)
		(fp_line
			(start 0.120396 0.3048)
			(end 0.120396 0.2794)
			(stroke
				(width 0.1)
				(type default)
			)
			(layer "F.Fab")
		)
		(fp_line
			(start 0.12065 -0.3048)
			(end 0.67945 -0.3048)
			(stroke
				(width 0.1)
				(type default)
			)
			(layer "F.Fab")
		)
		(fp_line
			(start 0.12065 -0.2794)
			(end 0.12065 -0.3048)
			(stroke
				(width 0.1)
				(type default)
			)
			(layer "F.Fab")
		)
		(fp_line
			(start 0.67945 -0.3048)
			(end 0.67945 0.3048)
			(stroke
				(width 0.1)
				(type default)
			)
			(layer "F.Fab")
		)
		(fp_line
			(start 0.67945 0.3048)
			(end 0.120396 0.3048)
			(stroke
				(width 0.1)
				(type default)
			)
			(layer "F.Fab")
		)
		(pad "1" smd circle
			(at -0.40005 0)
			(size 0 0)
			(layers "F.Cu" "F.Mask" "F.Paste")
			(net "SMB_HOST_3V3AUX_SDA_R4")
		)
		(pad "2" smd circle
			(at 0.40005 0)
			(size 0 0)
			(layers "F.Cu" "F.Mask" "F.Paste")
			(net "SMB_HOST_3V3AUX_PLD_SDA")
		)
	)
	(footprint ""
		(layer "F.Cu")
		(at 100.989384 -337.856068)
		(property "Reference" "PC561_P1_1"
			(at 0 0 0)
			(layer "F.SilkS")
			(hide yes)
			(effects
				(font
					(size 1.27 1.27)
				)
			)
		)
		(property "Value" ""
			(at 0 0 0)
			(layer "F.Fab")
			(effects
				(font
					(size 1.27 1.27)
				)
			)
		)
		(duplicate_pad_numbers_are_jumpers no)
		(fp_line
			(start -0.7874 -0.4064)
			(end 0.7874 -0.4064)
			(stroke
				(width 0.1524)
				(type default)
			)
			(layer "F.SilkS")
		)
		(fp_line
			(start -0.7874 0.4064)
			(end -0.7874 -0.4064)
			(stroke
				(width 0.1524)
				(type default)
			)
			(layer "F.SilkS")
		)
		(fp_line
			(start 0.7874 -0.4064)
			(end 0.7874 0.4064)
			(stroke
				(width 0.1524)
				(type default)
			)
			(layer "F.SilkS")
		)
		(fp_line
			(start 0.7874 0.4064)
			(end -0.7874 0.4064)
			(stroke
				(width 0.1524)
				(type default)
			)
			(layer "F.SilkS")
		)
		(fp_line
			(start -0.67945 -0.305054)
			(end -0.12065 -0.305054)
			(stroke
				(width 0.1)
				(type default)
			)
			(layer "F.Fab")
		)
		(fp_line
			(start -0.67945 0.3048)
			(end -0.67945 -0.305054)
			(stroke
				(width 0.1)
				(type default)
			)
			(layer "F.Fab")
		)
		(fp_line
			(start -0.12065 -0.305054)
			(end -0.12065 -0.2794)
			(stroke
				(width 0.1)
				(type default)
			)
			(layer "F.Fab")
		)
		(fp_line
			(start -0.12065 -0.2794)
			(end 0.12065 -0.2794)
			(stroke
				(width 0.1)
				(type default)
			)
			(layer "F.Fab")
		)
		(fp_line
			(start -0.12065 0.2794)
			(end -0.12065 0.3048)
			(stroke
				(width 0.1)
				(type default)
			)
			(layer "F.Fab")
		)
		(fp_line
			(start -0.12065 0.3048)
			(end -0.67945 0.3048)
			(stroke
				(width 0.1)
				(type default)
			)
			(layer "F.Fab")
		)
		(fp_line
			(start 0.120396 0.2794)
			(end -0.12065 0.2794)
			(stroke
				(width 0.1)
				(type default)
			)
			(layer "F.Fab")
		)
		(fp_line
			(start 0.120396 0.3048)
			(end 0.120396 0.2794)
			(stroke
				(width 0.1)
				(type default)
			)
			(layer "F.Fab")
		)
		(fp_line
			(start 0.12065 -0.3048)
			(end 0.67945 -0.3048)
			(stroke
				(width 0.1)
				(type default)
			)
			(layer "F.Fab")
		)
		(fp_line
			(start 0.12065 -0.2794)
			(end 0.12065 -0.3048)
			(stroke
				(width 0.1)
				(type default)
			)
			(layer "F.Fab")
		)
		(fp_line
			(start 0.67945 -0.3048)
			(end 0.67945 0.3048)
			(stroke
				(width 0.1)
				(type default)
			)
			(layer "F.Fab")
		)
		(fp_line
			(start 0.67945 0.3048)
			(end 0.120396 0.3048)
			(stroke
				(width 0.1)
				(type default)
			)
			(layer "F.Fab")
		)
		(pad "1" smd circle
			(at -0.40005 0)
			(size 0 0)
			(layers "F.Cu" "F.Mask" "F.Paste")
			(net "SW_P12V_PVCCIN_CPU1_FLT")
		)
		(pad "2" smd circle
			(at 0.40005 0)
			(size 0 0)
			(layers "F.Cu" "F.Mask" "F.Paste")
			(net "GND")
		)
	)
	(footprint ""
		(layer "F.Cu")
		(at 159.951674 -402.371052 -90)
		(property "Reference" "C769"
			(at 0 0 270)
			(layer "F.SilkS")
			(hide yes)
			(effects
				(font
					(size 1.27 1.27)
				)
			)
		)
		(property "Value" ""
			(at 0 0 270)
			(layer "F.Fab")
			(effects
				(font
					(size 1.27 1.27)
				)
			)
		)
		(duplicate_pad_numbers_are_jumpers no)
		(fp_line
			(start -0.299974 0.150114)
			(end -0.299974 -0.150114)
			(stroke
				(width 0.1)
				(type default)
			)
			(layer "F.Fab")
		)
		(fp_line
			(start 0.299974 0.150114)
			(end -0.299974 0.150114)
			(stroke
				(width 0.1)
				(type default)
			)
			(layer "F.Fab")
		)
		(fp_line
			(start -0.299974 -0.150114)
			(end 0.299974 -0.150114)
			(stroke
				(width 0.1)
				(type default)
			)
			(layer "F.Fab")
		)
		(fp_line
			(start 0.299974 -0.150114)
			(end 0.299974 0.150114)
			(stroke
				(width 0.1)
				(type default)
			)
			(layer "F.Fab")
		)
		(pad "1" smd rect
			(at -0.2667 0 270)
			(size 0.3048 0.381)
			(layers "F.Cu" "F.Mask" "F.Paste")
			(net "P5E_CPU1_PE2_TX_C_DP<2>")
		)
		(pad "2" smd rect
			(at 0.2667 0 270)
			(size 0.3048 0.381)
			(layers "F.Cu" "F.Mask" "F.Paste")
			(net "P5E_CPU1_PE2_TX_DP<2>")
		)
	)
	(footprint ""
		(layer "F.Cu")
		(at 101.071172 -363.873034)
		(property "Reference" "R2456"
			(at 0 0 0)
			(layer "F.SilkS")
			(hide yes)
			(effects
				(font
					(size 1.27 1.27)
				)
			)
		)
		(property "Value" ""
			(at 0 0 0)
			(layer "F.Fab")
			(effects
				(font
					(size 1.27 1.27)
				)
			)
		)
		(duplicate_pad_numbers_are_jumpers no)
		(fp_line
			(start -0.7874 -0.4064)
			(end 0.7874 -0.4064)
			(stroke
				(width 0.1524)
				(type default)
			)
			(layer "F.SilkS")
		)
		(fp_line
			(start -0.7874 0.4064)
			(end -0.7874 -0.4064)
			(stroke
				(width 0.1524)
				(type default)
			)
			(layer "F.SilkS")
		)
		(fp_line
			(start 0.7874 -0.4064)
			(end 0.7874 0.4064)
			(stroke
				(width 0.1524)
				(type default)
			)
			(layer "F.SilkS")
		)
		(fp_line
			(start 0.7874 0.4064)
			(end -0.7874 0.4064)
			(stroke
				(width 0.1524)
				(type default)
			)
			(layer "F.SilkS")
		)
		(fp_line
			(start -0.67945 -0.305054)
			(end -0.12065 -0.305054)
			(stroke
				(width 0.1)
				(type default)
			)
			(layer "F.Fab")
		)
		(fp_line
			(start -0.67945 0.3048)
			(end -0.67945 -0.305054)
			(stroke
				(width 0.1)
				(type default)
			)
			(layer "F.Fab")
		)
		(fp_line
			(start -0.12065 -0.305054)
			(end -0.12065 -0.2794)
			(stroke
				(width 0.1)
				(type default)
			)
			(layer "F.Fab")
		)
		(fp_line
			(start -0.12065 -0.2794)
			(end 0.12065 -0.2794)
			(stroke
				(width 0.1)
				(type default)
			)
			(layer "F.Fab")
		)
		(fp_line
			(start -0.12065 0.2794)
			(end -0.12065 0.3048)
			(stroke
				(width 0.1)
				(type default)
			)
			(layer "F.Fab")
		)
		(fp_line
			(start -0.12065 0.3048)
			(end -0.67945 0.3048)
			(stroke
				(width 0.1)
				(type default)
			)
			(layer "F.Fab")
		)
		(fp_line
			(start 0.120396 0.2794)
			(end -0.12065 0.2794)
			(stroke
				(width 0.1)
				(type default)
			)
			(layer "F.Fab")
		)
		(fp_line
			(start 0.120396 0.3048)
			(end 0.120396 0.2794)
			(stroke
				(width 0.1)
				(type default)
			)
			(layer "F.Fab")
		)
		(fp_line
			(start 0.12065 -0.3048)
			(end 0.67945 -0.3048)
			(stroke
				(width 0.1)
				(type default)
			)
			(layer "F.Fab")
		)
		(fp_line
			(start 0.12065 -0.2794)
			(end 0.12065 -0.3048)
			(stroke
				(width 0.1)
				(type default)
			)
			(layer "F.Fab")
		)
		(fp_line
			(start 0.67945 -0.3048)
			(end 0.67945 0.3048)
			(stroke
				(width 0.1)
				(type default)
			)
			(layer "F.Fab")
		)
		(fp_line
			(start 0.67945 0.3048)
			(end 0.120396 0.3048)
			(stroke
				(width 0.1)
				(type default)
			)
			(layer "F.Fab")
		)
		(pad "1" smd circle
			(at -0.40005 0)
			(size 0 0)
			(layers "F.Cu" "F.Mask" "F.Paste")
			(net "SMB_VR_3V3AUX_SDA_R")
		)
		(pad "2" smd circle
			(at 0.40005 0)
			(size 0 0)
			(layers "F.Cu" "F.Mask" "F.Paste")
			(net "SMB_VR_3V3AUX_SDA_R3")
		)
	)
	(footprint ""
		(layer "F.Cu")
		(at 296.831258 -372.456202 90)
		(property "Reference" "PC622"
			(at 0 0 90)
			(layer "F.SilkS")
			(hide yes)
			(effects
				(font
					(size 1.27 1.27)
				)
			)
		)
		(property "Value" ""
			(at 0 0 90)
			(layer "F.Fab")
			(effects
				(font
					(size 1.27 1.27)
				)
			)
		)
		(duplicate_pad_numbers_are_jumpers no)
		(fp_line
			(start -3.400044 1.249934)
			(end 3.400044 1.249934)
			(stroke
				(width 0.1524)
				(type default)
			)
			(layer "F.SilkS")
		)
		(fp_circle
			(center 0 1.249934)
			(end 0 4.649978)
			(stroke
				(width 0.1524)
				(type default)
			)
			(fill no)
			(layer "F.SilkS")
		)
		(fp_poly
			(pts
				(arc
					(start -3.400044 1.249934)
					(mid 0 4.649978)
					(end 3.400044 1.249934)
				)
			)
			(stroke
				(width 0)
				(type default)
			)
			(fill yes)
			(layer "F.SilkS")
		)
		(fp_circle
			(center 0 1.249934)
			(end 0 4.649978)
			(stroke
				(width 0.1)
				(type default)
			)
			(fill no)
			(layer "F.Fab")
		)
		(pad "1" thru_hole rect
			(at 0 0 90)
			(size 1.524 1.524)
			(drill 1.016)
			(layers "*.Cu" "*.Mask")
			(remove_unused_layers no)
			(net "SW_P12V_PVCCFA_EHV_FIVRA_CPU0_L")
			(clearance 0)
			(padstack
				(mode front_inner_back)
				(layer "Inner"
					(shape circle)
					(size 1.524 1.524)
					(clearance 0)
				)
				(layer "B.Cu"
					(shape rect)
					(size 1.524 1.524)
					(clearance 0)
				)
			)
		)
		(pad "2" thru_hole circle
			(at 0 2.500122 90)
			(size 1.524 1.524)
			(drill 1.016)
			(layers "*.Cu" "*.Mask")
			(remove_unused_layers no)
			(net "GND")
			(clearance 0)
		)
	)
	(footprint ""
		(layer "F.Cu")
		(at 64.591438 -31.887922 90)
		(property "Reference" "PC2167"
			(at 0 0 90)
			(layer "F.SilkS")
			(hide yes)
			(effects
				(font
					(size 1.27 1.27)
				)
			)
		)
		(property "Value" ""
			(at 0 0 90)
			(layer "F.Fab")
			(effects
				(font
					(size 1.27 1.27)
				)
			)
		)
		(duplicate_pad_numbers_are_jumpers no)
		(fp_line
			(start 0.7874 -0.4064)
			(end 0.7874 0.4064)
			(stroke
				(width 0.1524)
				(type default)
			)
			(layer "F.SilkS")
		)
		(fp_line
			(start -0.7874 -0.4064)
			(end 0.7874 -0.4064)
			(stroke
				(width 0.1524)
				(type default)
			)
			(layer "F.SilkS")
		)
		(fp_line
			(start 0.7874 0.4064)
			(end -0.7874 0.4064)
			(stroke
				(width 0.1524)
				(type default)
			)
			(layer "F.SilkS")
		)
		(fp_line
			(start -0.7874 0.4064)
			(end -0.7874 -0.4064)
			(stroke
				(width 0.1524)
				(type default)
			)
			(layer "F.SilkS")
		)
		(fp_line
			(start -0.12065 -0.305054)
			(end -0.12065 -0.2794)
			(stroke
				(width 0.1)
				(type default)
			)
			(layer "F.Fab")
		)
		(fp_line
			(start -0.67945 -0.305054)
			(end -0.12065 -0.305054)
			(stroke
				(width 0.1)
				(type default)
			)
			(layer "F.Fab")
		)
		(fp_line
			(start 0.67945 -0.3048)
			(end 0.67945 0.3048)
			(stroke
				(width 0.1)
				(type default)
			)
			(layer "F.Fab")
		)
		(fp_line
			(start 0.12065 -0.3048)
			(end 0.67945 -0.3048)
			(stroke
				(width 0.1)
				(type default)
			)
			(layer "F.Fab")
		)
		(fp_line
			(start 0.12065 -0.2794)
			(end 0.12065 -0.3048)
			(stroke
				(width 0.1)
				(type default)
			)
			(layer "F.Fab")
		)
		(fp_line
			(start -0.12065 -0.2794)
			(end 0.12065 -0.2794)
			(stroke
				(width 0.1)
				(type default)
			)
			(layer "F.Fab")
		)
		(fp_line
			(start 0.120396 0.2794)
			(end -0.12065 0.2794)
			(stroke
				(width 0.1)
				(type default)
			)
			(layer "F.Fab")
		)
		(fp_line
			(start -0.12065 0.2794)
			(end -0.12065 0.3048)
			(stroke
				(width 0.1)
				(type default)
			)
			(layer "F.Fab")
		)
		(fp_line
			(start 0.67945 0.3048)
			(end 0.120396 0.3048)
			(stroke
				(width 0.1)
				(type default)
			)
			(layer "F.Fab")
		)
		(fp_line
			(start 0.120396 0.3048)
			(end 0.120396 0.2794)
			(stroke
				(width 0.1)
				(type default)
			)
			(layer "F.Fab")
		)
		(fp_line
			(start -0.12065 0.3048)
			(end -0.67945 0.3048)
			(stroke
				(width 0.1)
				(type default)
			)
			(layer "F.Fab")
		)
		(fp_line
			(start -0.67945 0.3048)
			(end -0.67945 -0.305054)
			(stroke
				(width 0.1)
				(type default)
			)
			(layer "F.Fab")
		)
		(pad "1" smd circle
			(at -0.40005 0 90)
			(size 0 0)
			(layers "F.Cu" "F.Mask" "F.Paste")
			(net "P12V_OCP_IMON_2")
		)
		(pad "2" smd circle
			(at 0.40005 0 90)
			(size 0 0)
			(layers "F.Cu" "F.Mask" "F.Paste")
			(net "GND")
		)
	)
)
